(kicad_pcb
	(version 20260206)
	(generator "pcbnew")
	(generator_version "10.0")
	(general
		(thickness 1.6)
		(legacy_teardrops no)
	)
	(paper "A4")
	(title_block
		(title "01162023_DA0F0TEBIF0_F0T_Expander_BD_F_brd_V02_OCP.brd")
		(comment 1 "Grand Teton / footprints 1129-1135 of 9728")
	)
	(layers
		(0 "F.Cu" signal "TOP")
		(4 "In1.Cu" signal "GND")
		(6 "In2.Cu" signal "VCC")
		(8 "In3.Cu" signal "VCC1")
		(10 "In4.Cu" signal "GND1")
		(12 "In5.Cu" signal "IN1")
		(14 "In6.Cu" signal "GND2")
		(16 "In7.Cu" signal "IN2")
		(18 "In8.Cu" signal "GND3")
		(20 "In9.Cu" signal "IN3")
		(22 "In10.Cu" signal "GND4")
		(24 "In11.Cu" signal "IN4")
		(26 "In12.Cu" signal "GND5")
		(28 "In13.Cu" signal "IN5")
		(30 "In14.Cu" signal "GND6")
		(32 "In15.Cu" signal "IN6")
		(34 "In16.Cu" signal "GND7")
		(2 "B.Cu" signal "BOTTOM")
		(9 "F.Adhes" user "F.Adhesive")
		(11 "B.Adhes" user "B.Adhesive")
		(13 "F.Paste" user "Package Geometry/Pastemask Top")
		(15 "B.Paste" user "Package Geometry/Pastemask Bottom")
		(5 "F.SilkS" user "Ref Des/Silkscreen Top")
		(7 "B.SilkS" user "Ref Des/Silkscreen Bottom")
		(1 "F.Mask" user "Board Geometry/Soldermask Top")
		(3 "B.Mask" user "Board Geometry/Soldermask Bottom")
		(17 "Dwgs.User" user "User.Drawings")
		(19 "Cmts.User" user "User.Comments")
		(21 "Eco1.User" user "User.Eco1")
		(23 "Eco2.User" user "User.Eco2")
		(25 "Edge.Cuts" user "Board Geometry/Outline")
		(27 "Margin" user)
		(31 "F.CrtYd" user "Package Geometry/Place Bound Top")
		(29 "B.CrtYd" user "Package Geometry/Place Bound Bottom")
		(35 "F.Fab" user "Ref Des/Assembly Top")
		(33 "B.Fab" user "Ref Des/Assembly Bottom")
	)
	(footprint ""
		(layer "F.Cu")
		(at 457.726034 -305.241706)
		(property "Reference" "PC271"
			(at 0 0 0)
			(layer "F.SilkS")
			(hide yes)
			(effects
				(font
					(size 1.27 1.27)
				)
			)
		)
		(property "Value" ""
			(at 0 0 0)
			(layer "F.Fab")
			(effects
				(font
					(size 1.27 1.27)
				)
			)
		)
		(duplicate_pad_numbers_are_jumpers no)
		(fp_line
			(start -0.7874 -0.4064)
			(end 0.7874 -0.4064)
			(stroke
				(width 0.1524)
				(type default)
			)
			(layer "F.SilkS")
		)
		(fp_line
			(start -0.7874 0.4064)
			(end -0.7874 -0.4064)
			(stroke
				(width 0.1524)
				(type default)
			)
			(layer "F.SilkS")
		)
		(fp_line
			(start 0.7874 -0.4064)
			(end 0.7874 0.4064)
			(stroke
				(width 0.1524)
				(type default)
			)
			(layer "F.SilkS")
		)
		(fp_line
			(start 0.7874 0.4064)
			(end -0.7874 0.4064)
			(stroke
				(width 0.1524)
				(type default)
			)
			(layer "F.SilkS")
		)
		(fp_line
			(start -0.67945 -0.305054)
			(end -0.12065 -0.305054)
			(stroke
				(width 0.1)
				(type default)
			)
			(layer "F.Fab")
		)
		(fp_line
			(start -0.67945 0.3048)
			(end -0.67945 -0.305054)
			(stroke
				(width 0.1)
				(type default)
			)
			(layer "F.Fab")
		)
		(fp_line
			(start -0.12065 -0.305054)
			(end -0.12065 -0.2794)
			(stroke
				(width 0.1)
				(type default)
			)
			(layer "F.Fab")
		)
		(fp_line
			(start -0.12065 -0.2794)
			(end 0.12065 -0.2794)
			(stroke
				(width 0.1)
				(type default)
			)
			(layer "F.Fab")
		)
		(fp_line
			(start -0.12065 0.2794)
			(end -0.12065 0.3048)
			(stroke
				(width 0.1)
				(type default)
			)
			(layer "F.Fab")
		)
		(fp_line
			(start -0.12065 0.3048)
			(end -0.67945 0.3048)
			(stroke
				(width 0.1)
				(type default)
			)
			(layer "F.Fab")
		)
		(fp_line
			(start 0.120396 0.2794)
			(end -0.12065 0.2794)
			(stroke
				(width 0.1)
				(type default)
			)
			(layer "F.Fab")
		)
		(fp_line
			(start 0.120396 0.3048)
			(end 0.120396 0.2794)
			(stroke
				(width 0.1)
				(type default)
			)
			(layer "F.Fab")
		)
		(fp_line
			(start 0.12065 -0.3048)
			(end 0.67945 -0.3048)
			(stroke
				(width 0.1)
				(type default)
			)
			(layer "F.Fab")
		)
		(fp_line
			(start 0.12065 -0.2794)
			(end 0.12065 -0.3048)
			(stroke
				(width 0.1)
				(type default)
			)
			(layer "F.Fab")
		)
		(fp_line
			(start 0.67945 -0.3048)
			(end 0.67945 0.3048)
			(stroke
				(width 0.1)
				(type default)
			)
			(layer "F.Fab")
		)
		(fp_line
			(start 0.67945 0.3048)
			(end 0.120396 0.3048)
			(stroke
				(width 0.1)
				(type default)
			)
			(layer "F.Fab")
		)
		(pad "1" smd circle
			(at -0.40005 0)
			(size 0 0)
			(layers "F.Cu" "F.Mask" "F.Paste")
			(net "SW_P1V25_PEX3_BT")
		)
		(pad "2" smd circle
			(at 0.40005 0)
			(size 0 0)
			(layers "F.Cu" "F.Mask" "F.Paste")
			(net "SW_P1V25_PEX3_PH")
		)
	)
	(footprint ""
		(layer "F.Cu")
		(at 358.013 -220.472 180)
		(property "Reference" "R3648"
			(at 0 0 180)
			(layer "F.SilkS")
			(hide yes)
			(effects
				(font
					(size 1.27 1.27)
				)
			)
		)
		(property "Value" ""
			(at 0 0 180)
			(layer "F.Fab")
			(effects
				(font
					(size 1.27 1.27)
				)
			)
		)
		(duplicate_pad_numbers_are_jumpers no)
		(fp_line
			(start 0.7874 0.4064)
			(end -0.7874 0.4064)
			(stroke
				(width 0.1524)
				(type default)
			)
			(layer "F.SilkS")
		)
		(fp_line
			(start 0.7874 -0.4064)
			(end 0.7874 0.4064)
			(stroke
				(width 0.1524)
				(type default)
			)
			(layer "F.SilkS")
		)
		(fp_line
			(start -0.7874 0.4064)
			(end -0.7874 -0.4064)
			(stroke
				(width 0.1524)
				(type default)
			)
			(layer "F.SilkS")
		)
		(fp_line
			(start -0.7874 -0.4064)
			(end 0.7874 -0.4064)
			(stroke
				(width 0.1524)
				(type default)
			)
			(layer "F.SilkS")
		)
		(fp_line
			(start 0.67945 0.3048)
			(end 0.120396 0.3048)
			(stroke
				(width 0.1)
				(type default)
			)
			(layer "F.Fab")
		)
		(fp_line
			(start 0.67945 -0.3048)
			(end 0.67945 0.3048)
			(stroke
				(width 0.1)
				(type default)
			)
			(layer "F.Fab")
		)
		(fp_line
			(start 0.12065 -0.2794)
			(end 0.12065 -0.3048)
			(stroke
				(width 0.1)
				(type default)
			)
			(layer "F.Fab")
		)
		(fp_line
			(start 0.12065 -0.3048)
			(end 0.67945 -0.3048)
			(stroke
				(width 0.1)
				(type default)
			)
			(layer "F.Fab")
		)
		(fp_line
			(start 0.120396 0.3048)
			(end 0.120396 0.2794)
			(stroke
				(width 0.1)
				(type default)
			)
			(layer "F.Fab")
		)
		(fp_line
			(start 0.120396 0.2794)
			(end -0.12065 0.2794)
			(stroke
				(width 0.1)
				(type default)
			)
			(layer "F.Fab")
		)
		(fp_line
			(start -0.12065 0.3048)
			(end -0.67945 0.3048)
			(stroke
				(width 0.1)
				(type default)
			)
			(layer "F.Fab")
		)
		(fp_line
			(start -0.12065 0.2794)
			(end -0.12065 0.3048)
			(stroke
				(width 0.1)
				(type default)
			)
			(layer "F.Fab")
		)
		(fp_line
			(start -0.12065 -0.2794)
			(end 0.12065 -0.2794)
			(stroke
				(width 0.1)
				(type default)
			)
			(layer "F.Fab")
		)
		(fp_line
			(start -0.12065 -0.305054)
			(end -0.12065 -0.2794)
			(stroke
				(width 0.1)
				(type default)
			)
			(layer "F.Fab")
		)
		(fp_line
			(start -0.67945 0.3048)
			(end -0.67945 -0.305054)
			(stroke
				(width 0.1)
				(type default)
			)
			(layer "F.Fab")
		)
		(fp_line
			(start -0.67945 -0.305054)
			(end -0.12065 -0.305054)
			(stroke
				(width 0.1)
				(type default)
			)
			(layer "F.Fab")
		)
		(pad "1" smd circle
			(at -0.40005 0 180)
			(size 0 0)
			(layers "F.Cu" "F.Mask" "F.Paste")
			(net "NIC5_CLK_EN_R_N")
		)
		(pad "2" smd circle
			(at 0.40005 0 180)
			(size 0 0)
			(layers "F.Cu" "F.Mask" "F.Paste")
			(net "NIC5_CLK_EN_N")
		)
	)
	(footprint ""
		(layer "F.Cu")
		(at 353.247452 -36.686998 90)
		(property "Reference" "C3672"
			(at 0 0 90)
			(layer "F.SilkS")
			(hide yes)
			(effects
				(font
					(size 1.27 1.27)
				)
			)
		)
		(property "Value" ""
			(at 0 0 90)
			(layer "F.Fab")
			(effects
				(font
					(size 1.27 1.27)
				)
			)
		)
		(duplicate_pad_numbers_are_jumpers no)
		(fp_line
			(start 0.7874 -0.4064)
			(end 0.7874 0.4064)
			(stroke
				(width 0.1524)
				(type default)
			)
			(layer "F.SilkS")
		)
		(fp_line
			(start -0.7874 -0.4064)
			(end 0.7874 -0.4064)
			(stroke
				(width 0.1524)
				(type default)
			)
			(layer "F.SilkS")
		)
		(fp_line
			(start 0.7874 0.4064)
			(end -0.7874 0.4064)
			(stroke
				(width 0.1524)
				(type default)
			)
			(layer "F.SilkS")
		)
		(fp_line
			(start -0.7874 0.4064)
			(end -0.7874 -0.4064)
			(stroke
				(width 0.1524)
				(type default)
			)
			(layer "F.SilkS")
		)
		(fp_line
			(start -0.12065 -0.305054)
			(end -0.12065 -0.2794)
			(stroke
				(width 0.1)
				(type default)
			)
			(layer "F.Fab")
		)
		(fp_line
			(start -0.67945 -0.305054)
			(end -0.12065 -0.305054)
			(stroke
				(width 0.1)
				(type default)
			)
			(layer "F.Fab")
		)
		(fp_line
			(start 0.67945 -0.3048)
			(end 0.67945 0.3048)
			(stroke
				(width 0.1)
				(type default)
			)
			(layer "F.Fab")
		)
		(fp_line
			(start 0.12065 -0.3048)
			(end 0.67945 -0.3048)
			(stroke
				(width 0.1)
				(type default)
			)
			(layer "F.Fab")
		)
		(fp_line
			(start 0.12065 -0.2794)
			(end 0.12065 -0.3048)
			(stroke
				(width 0.1)
				(type default)
			)
			(layer "F.Fab")
		)
		(fp_line
			(start -0.12065 -0.2794)
			(end 0.12065 -0.2794)
			(stroke
				(width 0.1)
				(type default)
			)
			(layer "F.Fab")
		)
		(fp_line
			(start 0.120396 0.2794)
			(end -0.12065 0.2794)
			(stroke
				(width 0.1)
				(type default)
			)
			(layer "F.Fab")
		)
		(fp_line
			(start -0.12065 0.2794)
			(end -0.12065 0.3048)
			(stroke
				(width 0.1)
				(type default)
			)
			(layer "F.Fab")
		)
		(fp_line
			(start 0.67945 0.3048)
			(end 0.120396 0.3048)
			(stroke
				(width 0.1)
				(type default)
			)
			(layer "F.Fab")
		)
		(fp_line
			(start 0.120396 0.3048)
			(end 0.120396 0.2794)
			(stroke
				(width 0.1)
				(type default)
			)
			(layer "F.Fab")
		)
		(fp_line
			(start -0.12065 0.3048)
			(end -0.67945 0.3048)
			(stroke
				(width 0.1)
				(type default)
			)
			(layer "F.Fab")
		)
		(fp_line
			(start -0.67945 0.3048)
			(end -0.67945 -0.305054)
			(stroke
				(width 0.1)
				(type default)
			)
			(layer "F.Fab")
		)
		(pad "1" smd circle
			(at -0.40005 0 90)
			(size 0 0)
			(layers "F.Cu" "F.Mask" "F.Paste")
			(net "P3V3_AUX")
		)
		(pad "2" smd circle
			(at 0.40005 0 90)
			(size 0 0)
			(layers "F.Cu" "F.Mask" "F.Paste")
			(net "GND")
		)
	)
	(footprint ""
		(layer "F.Cu")
		(at 259.152644 -262.649208 90)
		(property "Reference" "C3412"
			(at 0 0 90)
			(layer "F.SilkS")
			(hide yes)
			(effects
				(font
					(size 1.27 1.27)
				)
			)
		)
		(property "Value" ""
			(at 0 0 90)
			(layer "F.Fab")
			(effects
				(font
					(size 1.27 1.27)
				)
			)
		)
		(duplicate_pad_numbers_are_jumpers no)
		(fp_line
			(start 0.299974 -0.150114)
			(end 0.299974 0.150114)
			(stroke
				(width 0.1)
				(type default)
			)
			(layer "F.Fab")
		)
		(fp_line
			(start -0.299974 -0.150114)
			(end 0.299974 -0.150114)
			(stroke
				(width 0.1)
				(type default)
			)
			(layer "F.Fab")
		)
		(fp_line
			(start 0.299974 0.150114)
			(end -0.299974 0.150114)
			(stroke
				(width 0.1)
				(type default)
			)
			(layer "F.Fab")
		)
		(fp_line
			(start -0.299974 0.150114)
			(end -0.299974 -0.150114)
			(stroke
				(width 0.1)
				(type default)
			)
			(layer "F.Fab")
		)
		(pad "1" smd rect
			(at -0.2667 0 90)
			(size 0.3048 0.381)
			(layers "F.Cu" "F.Mask" "F.Paste")
			(net "P1V8_PLL0_PEX2")
		)
		(pad "2" smd rect
			(at 0.2667 0 90)
			(size 0.3048 0.381)
			(layers "F.Cu" "F.Mask" "F.Paste")
			(net "GND")
		)
	)
	(footprint ""
		(layer "F.Cu")
		(at 334.315308 -42.853102 180)
		(property "Reference" "R5902"
			(at 0 0 180)
			(layer "F.SilkS")
			(hide yes)
			(effects
				(font
					(size 1.27 1.27)
				)
			)
		)
		(property "Value" ""
			(at 0 0 180)
			(layer "F.Fab")
			(effects
				(font
					(size 1.27 1.27)
				)
			)
		)
		(duplicate_pad_numbers_are_jumpers no)
		(fp_line
			(start 0.7874 0.4064)
			(end -0.7874 0.4064)
			(stroke
				(width 0.1524)
				(type default)
			)
			(layer "F.SilkS")
		)
		(fp_line
			(start 0.7874 -0.4064)
			(end 0.7874 0.4064)
			(stroke
				(width 0.1524)
				(type default)
			)
			(layer "F.SilkS")
		)
		(fp_line
			(start -0.7874 0.4064)
			(end -0.7874 -0.4064)
			(stroke
				(width 0.1524)
				(type default)
			)
			(layer "F.SilkS")
		)
		(fp_line
			(start -0.7874 -0.4064)
			(end 0.7874 -0.4064)
			(stroke
				(width 0.1524)
				(type default)
			)
			(layer "F.SilkS")
		)
		(fp_line
			(start 0.67945 0.3048)
			(end 0.120396 0.3048)
			(stroke
				(width 0.1)
				(type default)
			)
			(layer "F.Fab")
		)
		(fp_line
			(start 0.67945 -0.3048)
			(end 0.67945 0.3048)
			(stroke
				(width 0.1)
				(type default)
			)
			(layer "F.Fab")
		)
		(fp_line
			(start 0.12065 -0.2794)
			(end 0.12065 -0.3048)
			(stroke
				(width 0.1)
				(type default)
			)
			(layer "F.Fab")
		)
		(fp_line
			(start 0.12065 -0.3048)
			(end 0.67945 -0.3048)
			(stroke
				(width 0.1)
				(type default)
			)
			(layer "F.Fab")
		)
		(fp_line
			(start 0.120396 0.3048)
			(end 0.120396 0.2794)
			(stroke
				(width 0.1)
				(type default)
			)
			(layer "F.Fab")
		)
		(fp_line
			(start 0.120396 0.2794)
			(end -0.12065 0.2794)
			(stroke
				(width 0.1)
				(type default)
			)
			(layer "F.Fab")
		)
		(fp_line
			(start -0.12065 0.3048)
			(end -0.67945 0.3048)
			(stroke
				(width 0.1)
				(type default)
			)
			(layer "F.Fab")
		)
		(fp_line
			(start -0.12065 0.2794)
			(end -0.12065 0.3048)
			(stroke
				(width 0.1)
				(type default)
			)
			(layer "F.Fab")
		)
		(fp_line
			(start -0.12065 -0.2794)
			(end 0.12065 -0.2794)
			(stroke
				(width 0.1)
				(type default)
			)
			(layer "F.Fab")
		)
		(fp_line
			(start -0.12065 -0.305054)
			(end -0.12065 -0.2794)
			(stroke
				(width 0.1)
				(type default)
			)
			(layer "F.Fab")
		)
		(fp_line
			(start -0.67945 0.3048)
			(end -0.67945 -0.305054)
			(stroke
				(width 0.1)
				(type default)
			)
			(layer "F.Fab")
		)
		(fp_line
			(start -0.67945 -0.305054)
			(end -0.12065 -0.305054)
			(stroke
				(width 0.1)
				(type default)
			)
			(layer "F.Fab")
		)
		(pad "1" smd circle
			(at -0.40005 0 180)
			(size 0 0)
			(layers "F.Cu" "F.Mask" "F.Paste")
			(net "SSD11_ADC_A1")
		)
		(pad "2" smd circle
			(at 0.40005 0 180)
			(size 0 0)
			(layers "F.Cu" "F.Mask" "F.Paste")
			(net "SMB_SSD11_ADC_SDA")
		)
	)
	(footprint ""
		(layer "F.Cu")
		(at 217.235786 -222.366586 180)
		(property "Reference" "R1491"
			(at 0 0 180)
			(layer "F.SilkS")
			(hide yes)
			(effects
				(font
					(size 1.27 1.27)
				)
			)
		)
		(property "Value" ""
			(at 0 0 180)
			(layer "F.Fab")
			(effects
				(font
					(size 1.27 1.27)
				)
			)
		)
		(duplicate_pad_numbers_are_jumpers no)
		(fp_line
			(start 0.7874 0.4064)
			(end -0.7874 0.4064)
			(stroke
				(width 0.1524)
				(type default)
			)
			(layer "F.SilkS")
		)
		(fp_line
			(start 0.7874 -0.4064)
			(end 0.7874 0.4064)
			(stroke
				(width 0.1524)
				(type default)
			)
			(layer "F.SilkS")
		)
		(fp_line
			(start -0.7874 0.4064)
			(end -0.7874 -0.4064)
			(stroke
				(width 0.1524)
				(type default)
			)
			(layer "F.SilkS")
		)
		(fp_line
			(start -0.7874 -0.4064)
			(end 0.7874 -0.4064)
			(stroke
				(width 0.1524)
				(type default)
			)
			(layer "F.SilkS")
		)
		(fp_line
			(start 0.67945 0.3048)
			(end 0.120396 0.3048)
			(stroke
				(width 0.1)
				(type default)
			)
			(layer "F.Fab")
		)
		(fp_line
			(start 0.67945 -0.3048)
			(end 0.67945 0.3048)
			(stroke
				(width 0.1)
				(type default)
			)
			(layer "F.Fab")
		)
		(fp_line
			(start 0.12065 -0.2794)
			(end 0.12065 -0.3048)
			(stroke
				(width 0.1)
				(type default)
			)
			(layer "F.Fab")
		)
		(fp_line
			(start 0.12065 -0.3048)
			(end 0.67945 -0.3048)
			(stroke
				(width 0.1)
				(type default)
			)
			(layer "F.Fab")
		)
		(fp_line
			(start 0.120396 0.3048)
			(end 0.120396 0.2794)
			(stroke
				(width 0.1)
				(type default)
			)
			(layer "F.Fab")
		)
		(fp_line
			(start 0.120396 0.2794)
			(end -0.12065 0.2794)
			(stroke
				(width 0.1)
				(type default)
			)
			(layer "F.Fab")
		)
		(fp_line
			(start -0.12065 0.3048)
			(end -0.67945 0.3048)
			(stroke
				(width 0.1)
				(type default)
			)
			(layer "F.Fab")
		)
		(fp_line
			(start -0.12065 0.2794)
			(end -0.12065 0.3048)
			(stroke
				(width 0.1)
				(type default)
			)
			(layer "F.Fab")
		)
		(fp_line
			(start -0.12065 -0.2794)
			(end 0.12065 -0.2794)
			(stroke
				(width 0.1)
				(type default)
			)
			(layer "F.Fab")
		)
		(fp_line
			(start -0.12065 -0.305054)
			(end -0.12065 -0.2794)
			(stroke
				(width 0.1)
				(type default)
			)
			(layer "F.Fab")
		)
		(fp_line
			(start -0.67945 0.3048)
			(end -0.67945 -0.305054)
			(stroke
				(width 0.1)
				(type default)
			)
			(layer "F.Fab")
		)
		(fp_line
			(start -0.67945 -0.305054)
			(end -0.12065 -0.305054)
			(stroke
				(width 0.1)
				(type default)
			)
			(layer "F.Fab")
		)
		(pad "1" smd circle
			(at -0.40005 0 180)
			(size 0 0)
			(layers "F.Cu" "F.Mask" "F.Paste")
			(net "SMB_BIC_I2C9_SSD_MUX_SCL")
		)
		(pad "2" smd circle
			(at 0.40005 0 180)
			(size 0 0)
			(layers "F.Cu" "F.Mask" "F.Paste")
			(net "SMB_BIC_I2C9_SSD_MUX_R_SCL")
		)
	)
	(footprint ""
		(layer "F.Cu")
		(at 132.352796 -159.173418 90)
		(property "Reference" "PC619"
			(at 0 0 90)
			(layer "F.SilkS")
			(hide yes)
			(effects
				(font
					(size 1.27 1.27)
				)
			)
		)
		(property "Value" ""
			(at 0 0 90)
			(layer "F.Fab")
			(effects
				(font
					(size 1.27 1.27)
				)
			)
		)
		(duplicate_pad_numbers_are_jumpers no)
		(fp_line
			(start 0.7874 -0.4064)
			(end 0.7874 0.4064)
			(stroke
				(width 0.1524)
				(type default)
			)
			(layer "F.SilkS")
		)
		(fp_line
			(start -0.7874 -0.4064)
			(end 0.7874 -0.4064)
			(stroke
				(width 0.1524)
				(type default)
			)
			(layer "F.SilkS")
		)
		(fp_line
			(start 0.7874 0.4064)
			(end -0.7874 0.4064)
			(stroke
				(width 0.1524)
				(type default)
			)
			(layer "F.SilkS")
		)
		(fp_line
			(start -0.7874 0.4064)
			(end -0.7874 -0.4064)
			(stroke
				(width 0.1524)
				(type default)
			)
			(layer "F.SilkS")
		)
		(fp_line
			(start -0.12065 -0.305054)
			(end -0.12065 -0.2794)
			(stroke
				(width 0.1)
				(type default)
			)
			(layer "F.Fab")
		)
		(fp_line
			(start -0.67945 -0.305054)
			(end -0.12065 -0.305054)
			(stroke
				(width 0.1)
				(type default)
			)
			(layer "F.Fab")
		)
		(fp_line
			(start 0.67945 -0.3048)
			(end 0.67945 0.3048)
			(stroke
				(width 0.1)
				(type default)
			)
			(layer "F.Fab")
		)
		(fp_line
			(start 0.12065 -0.3048)
			(end 0.67945 -0.3048)
			(stroke
				(width 0.1)
				(type default)
			)
			(layer "F.Fab")
		)
		(fp_line
			(start 0.12065 -0.2794)
			(end 0.12065 -0.3048)
			(stroke
				(width 0.1)
				(type default)
			)
			(layer "F.Fab")
		)
		(fp_line
			(start -0.12065 -0.2794)
			(end 0.12065 -0.2794)
			(stroke
				(width 0.1)
				(type default)
			)
			(layer "F.Fab")
		)
		(fp_line
			(start 0.120396 0.2794)
			(end -0.12065 0.2794)
			(stroke
				(width 0.1)
				(type default)
			)
			(layer "F.Fab")
		)
		(fp_line
			(start -0.12065 0.2794)
			(end -0.12065 0.3048)
			(stroke
				(width 0.1)
				(type default)
			)
			(layer "F.Fab")
		)
		(fp_line
			(start 0.67945 0.3048)
			(end 0.120396 0.3048)
			(stroke
				(width 0.1)
				(type default)
			)
			(layer "F.Fab")
		)
		(fp_line
			(start 0.120396 0.3048)
			(end 0.120396 0.2794)
			(stroke
				(width 0.1)
				(type default)
			)
			(layer "F.Fab")
		)
		(fp_line
			(start -0.12065 0.3048)
			(end -0.67945 0.3048)
			(stroke
				(width 0.1)
				(type default)
			)
			(layer "F.Fab")
		)
		(fp_line
			(start -0.67945 0.3048)
			(end -0.67945 -0.305054)
			(stroke
				(width 0.1)
				(type default)
			)
			(layer "F.Fab")
		)
		(pad "1" smd circle
			(at -0.40005 0 90)
			(size 0 0)
			(layers "F.Cu" "F.Mask" "F.Paste")
			(net "P12V_AUX")
		)
		(pad "2" smd circle
			(at 0.40005 0 90)
			(size 0 0)
			(layers "F.Cu" "F.Mask" "F.Paste")
			(net "GND")
		)
	)
)
